(kicad_pcb
	(version 20241229)
	(generator "pcbnew")
	(generator_version "9.0")
	(general
		(thickness 1.61)
		(legacy_teardrops no)
	)
	(paper "A3")
	(title_block
		(title "RDIMM DDR5 Tester")
		(date "2026-05-21")
		(rev "2.2.0")
		(company "Antmicro")
		(comment 9 "footprints 223-226 of 796")
	)
	(layers
		(0 "F.Cu" signal)
		(4 "In1.Cu" power)
		(6 "In2.Cu" mixed)
		(8 "In3.Cu" power)
		(10 "In4.Cu" mixed)
		(12 "In5.Cu" power)
		(14 "In6.Cu" mixed)
		(16 "In7.Cu" power)
		(18 "In8.Cu" power)
		(20 "In9.Cu" mixed)
		(22 "In10.Cu" power)
		(2 "B.Cu" signal)
		(9 "F.Adhes" user "F.Adhesive")
		(11 "B.Adhes" user "B.Adhesive")
		(13 "F.Paste" user)
		(15 "B.Paste" user)
		(5 "F.SilkS" user "F.Silkscreen")
		(7 "B.SilkS" user "B.Silkscreen")
		(1 "F.Mask" user)
		(3 "B.Mask" user)
		(17 "Dwgs.User" user "User.Drawings")
		(19 "Cmts.User" user "User.Comments")
		(21 "Eco1.User" user "User.Eco1")
		(23 "Eco2.User" user "User.Eco2")
		(25 "Edge.Cuts" user)
		(27 "Margin" user)
		(31 "F.CrtYd" user "F.Courtyard")
		(29 "B.CrtYd" user "B.Courtyard")
		(35 "F.Fab" user)
		(33 "B.Fab" user)
	)
	(footprint "antmicro-footprints:R_0402_1005Metric"
		(layer "F.Cu")
		(at 253.42 167.8595 180)
		(descr "Resistor SMD 0402")
		(tags "resistor SMD 0402")
		(property "Reference" "R154"
			(at -1.28 0.4595 0)
			(layer "F.SilkS")
			(effects
				(font
					(size 0.7 0.7)
					(thickness 0.15)
				)
				(justify right bottom)
			)
		)
		(property "Value" "R_0R_0402"
			(at -1.011843 1.772047 0)
			(layer "F.Fab")
			(effects
				(font
					(size 0.7 0.7)
					(thickness 0.15)
				)
				(justify right bottom)
			)
		)
		(property "Datasheet" "https://industrial.panasonic.com/cdbs/www-data/pdf/RDA0000/AOA0000C301.pdf"
			(at 0 0 180)
			(layer "F.Fab")
			(hide yes)
			(effects
				(font
					(size 1.27 1.27)
					(thickness 0.15)
				)
			)
		)
		(property "Manufacturer" "Panasonic"
			(at 0 0 180)
			(unlocked yes)
			(layer "F.Fab")
			(hide yes)
			(effects
				(font
					(size 1 1)
					(thickness 0.15)
				)
			)
		)
		(property "MPN" "ERJ2GE0R00X"
			(at 0 0 180)
			(unlocked yes)
			(layer "F.Fab")
			(hide yes)
			(effects
				(font
					(size 1 1)
					(thickness 0.15)
				)
			)
		)
		(property "Val" "0R"
			(at 0 0 180)
			(unlocked yes)
			(layer "F.Fab")
			(hide yes)
			(effects
				(font
					(size 1 1)
					(thickness 0.15)
				)
			)
		)
		(property "License" "Apache-2.0"
			(at 0 0 180)
			(unlocked yes)
			(layer "F.Fab")
			(hide yes)
			(effects
				(font
					(size 1 1)
					(thickness 0.15)
				)
			)
		)
		(property "Author" "Antmicro"
			(at 0 0 180)
			(unlocked yes)
			(layer "F.Fab")
			(hide yes)
			(effects
				(font
					(size 1 1)
					(thickness 0.15)
				)
			)
		)
		(property "Tolerance" "~"
			(at 0 0 180)
			(unlocked yes)
			(layer "F.Fab")
			(hide yes)
			(effects
				(font
					(size 1 1)
					(thickness 0.15)
				)
			)
		)
		(property "Current" "1A"
			(at 0 0 180)
			(unlocked yes)
			(layer "F.Fab")
			(hide yes)
			(effects
				(font
					(size 1 1)
					(thickness 0.15)
				)
			)
		)
		(sheetname "/Supply/DC-DC AUX, MGT/")
		(sheetfile "dc-dc-aux-mgt.kicad_sch")
		(attr smd)
		(fp_rect
			(start -0.925 -0.47)
			(end 0.925 0.47)
			(stroke
				(width 0.05)
				(type default)
			)
			(fill no)
			(layer "F.CrtYd")
		)
		(fp_rect
			(start -0.5 -0.25)
			(end 0.5 0.25)
			(stroke
				(width 0.15)
				(type solid)
			)
			(fill no)
			(layer "F.Fab")
		)
		(fp_text user "${REFERENCE}"
			(at -0.95 3.168 180)
			(layer "F.Fab")
			(effects
				(font
					(size 0.7 0.7)
					(thickness 0.15)
				)
				(justify left bottom)
			)
		)
		(fp_text user "Author: Antmicro"
			(at -0.95 4.169 180)
			(layer "F.Fab")
			(effects
				(font
					(size 0.7 0.7)
					(thickness 0.15)
				)
				(justify left bottom)
			)
		)
		(fp_text user "License: Apache-2.0"
			(at -0.95 5.169 180)
			(layer "F.Fab")
			(effects
				(font
					(size 0.7 0.7)
					(thickness 0.15)
				)
				(justify left bottom)
			)
		)
		(pad "1" smd roundrect
			(at -0.48 0 180)
			(size 0.59 0.64)
			(layers "F.Cu" "F.Mask" "F.Paste")
			(roundrect_rratio 0.25)
			(net 713 "/Supply/DC-DC AUX, MGT/FB2")
			(pintype "passive")
		)
		(pad "2" smd roundrect
			(at 0.48 0 180)
			(size 0.59 0.64)
			(layers "F.Cu" "F.Mask" "F.Paste")
			(roundrect_rratio 0.25)
			(net 48 "/Supply/DC-DC AUX, MGT/MGTAVTT_local")
			(pintype "passive")
		)
	)
	(footprint "antmicro-footprints:QFN-2L_1.6x1x0.55mm"
		(layer "F.Cu")
		(at 243.449499 122.3 90)
		(property "Reference" "D16"
			(at -1.391 -0.779499 90)
			(layer "F.SilkS")
			(effects
				(font
					(size 0.7 0.7)
					(thickness 0.15)
				)
				(justify left bottom)
			)
		)
		(property "Value" "ESDA25P35-1U1M"
			(at 0 1.7 90)
			(layer "F.Fab")
			(effects
				(font
					(size 0.7 0.7)
					(thickness 0.15)
				)
				(justify left bottom)
			)
		)
		(property "Datasheet" "https://www.st.com/resource/en/datasheet/esda25p35-1u1m.pdf"
			(at 0 0 90)
			(layer "F.Fab")
			(hide yes)
			(effects
				(font
					(size 1.27 1.27)
					(thickness 0.15)
				)
			)
		)
		(property "MPN" "ESDA25P35-1U1M"
			(at 0 0 90)
			(unlocked yes)
			(layer "F.Fab")
			(hide yes)
			(effects
				(font
					(size 1 1)
					(thickness 0.15)
				)
			)
		)
		(property "Manufacturer" "STMicroelectronics"
			(at 0 0 90)
			(unlocked yes)
			(layer "F.Fab")
			(hide yes)
			(effects
				(font
					(size 1 1)
					(thickness 0.15)
				)
			)
		)
		(property "Author" "Antmicro"
			(at 0 0 90)
			(unlocked yes)
			(layer "F.Fab")
			(hide yes)
			(effects
				(font
					(size 1 1)
					(thickness 0.15)
				)
			)
		)
		(property "License" "Apache-2.0"
			(at 0 0 90)
			(unlocked yes)
			(layer "F.Fab")
			(hide yes)
			(effects
				(font
					(size 1 1)
					(thickness 0.15)
				)
			)
		)
		(sheetname "/Supply/")
		(sheetfile "supply.kicad_sch")
		(attr smd)
		(fp_line
			(start 0.23 -0.45)
			(end -0.23 -0.45)
			(stroke
				(width 0.15)
				(type solid)
			)
			(layer "F.SilkS")
		)
		(fp_line
			(start -1.2 -0.4)
			(end -1.2 0.4)
			(stroke
				(width 0.15)
				(type solid)
			)
			(layer "F.SilkS")
		)
		(fp_line
			(start 0.23 0.45)
			(end -0.23 0.45)
			(stroke
				(width 0.15)
				(type solid)
			)
			(layer "F.SilkS")
		)
		(fp_rect
			(start 1.25 0.65)
			(end -1.25 -0.65)
			(stroke
				(width 0.05)
				(type solid)
			)
			(fill no)
			(layer "F.CrtYd")
		)
		(fp_line
			(start 0.201 -0.202)
			(end -0.101 0)
			(stroke
				(width 0.15)
				(type solid)
			)
			(layer "F.Fab")
		)
		(fp_line
			(start -0.199 -0.202)
			(end -0.199 0.1)
			(stroke
				(width 0.15)
				(type solid)
			)
			(layer "F.Fab")
		)
		(fp_line
			(start 0.599 0)
			(end 0.201 0)
			(stroke
				(width 0.15)
				(type solid)
			)
			(layer "F.Fab")
		)
		(fp_line
			(start 0.201 0)
			(end 0.201 -0.202)
			(stroke
				(width 0.15)
				(type solid)
			)
			(layer "F.Fab")
		)
		(fp_line
			(start -0.101 0)
			(end 0.201 0.2)
			(stroke
				(width 0.15)
				(type solid)
			)
			(layer "F.Fab")
		)
		(fp_line
			(start -0.199 0)
			(end -0.597 0)
			(stroke
				(width 0.15)
				(type solid)
			)
			(layer "F.Fab")
		)
		(fp_line
			(start 0.201 0.2)
			(end 0.201 0)
			(stroke
				(width 0.15)
				(type solid)
			)
			(layer "F.Fab")
		)
		(fp_line
			(start -0.199 0.2)
			(end -0.199 0.1)
			(stroke
				(width 0.15)
				(type solid)
			)
			(layer "F.Fab")
		)
		(fp_rect
			(start 0.848 0.4)
			(end -0.85 -0.402)
			(stroke
				(width 0.15)
				(type solid)
			)
			(fill no)
			(layer "F.Fab")
		)
		(fp_text user "License: Apache-2.0"
			(at -1.31 5.769 90)
			(layer "F.Fab")
			(effects
				(font
					(size 0.7 0.7)
					(thickness 0.15)
				)
				(justify left bottom)
			)
		)
		(fp_text user "Author: Antmicro"
			(at -1.31 4.769 90)
			(layer "F.Fab")
			(effects
				(font
					(size 0.7 0.7)
					(thickness 0.15)
				)
				(justify left bottom)
			)
		)
		(fp_text user "${REFERENCE}"
			(at -1.31 3.769 90)
			(layer "F.Fab")
			(effects
				(font
					(size 0.7 0.7)
					(thickness 0.15)
				)
				(justify left bottom)
			)
		)
		(pad "1" smd roundrect
			(at -0.7 0 270)
			(size 0.8 1)
			(layers "F.Cu" "F.Mask" "F.Paste")
			(roundrect_rratio 0.2)
			(net 323 "/Supply/12V_aux_fused")
			(pinfunction "C")
			(pintype "passive")
		)
		(pad "2" smd roundrect
			(at 0.7 0 270)
			(size 0.8 1)
			(layers "F.Cu" "F.Mask" "F.Paste")
			(roundrect_rratio 0.2)
			(net 1 "GND")
			(pinfunction "A")
			(pintype "passive")
		)
	)
	(footprint "antmicro-footprints:R_0402_1005Metric"
		(layer "F.Cu")
		(at 112.037258 171.5335 -90)
		(descr "Resistor SMD 0402")
		(tags "resistor SMD 0402")
		(property "Reference" "R89"
			(at 0.9165 -0.362742 90)
			(layer "F.SilkS")
			(effects
				(font
					(size 0.7 0.7)
					(thickness 0.15)
				)
				(justify right bottom)
			)
		)
		(property "Value" "R_330R_0402"
			(at -1.011843 1.772047 90)
			(layer "F.Fab")
			(effects
				(font
					(size 0.7 0.7)
					(thickness 0.15)
				)
				(justify right bottom)
			)
		)
		(property "Datasheet" "https://www.bourns.com/docs/product-datasheets/cr.pdf"
			(at 0 0 270)
			(layer "F.Fab")
			(hide yes)
			(effects
				(font
					(size 1.27 1.27)
					(thickness 0.15)
				)
			)
		)
		(property "Manufacturer" "Bourns"
			(at 0 0 270)
			(unlocked yes)
			(layer "F.Fab")
			(hide yes)
			(effects
				(font
					(size 1 1)
					(thickness 0.15)
				)
			)
		)
		(property "MPN" "CR0402-FX-3300GLF"
			(at 0 0 270)
			(unlocked yes)
			(layer "F.Fab")
			(hide yes)
			(effects
				(font
					(size 1 1)
					(thickness 0.15)
				)
			)
		)
		(property "Val" "330R"
			(at 0 0 270)
			(unlocked yes)
			(layer "F.Fab")
			(hide yes)
			(effects
				(font
					(size 1 1)
					(thickness 0.15)
				)
			)
		)
		(property "License" "Apache-2.0"
			(at 0 0 270)
			(unlocked yes)
			(layer "F.Fab")
			(hide yes)
			(effects
				(font
					(size 1 1)
					(thickness 0.15)
				)
			)
		)
		(property "Author" "Antmicro"
			(at 0 0 270)
			(unlocked yes)
			(layer "F.Fab")
			(hide yes)
			(effects
				(font
					(size 1 1)
					(thickness 0.15)
				)
			)
		)
		(property "Tolerance" "1%"
			(at 0 0 270)
			(unlocked yes)
			(layer "F.Fab")
			(hide yes)
			(effects
				(font
					(size 1 1)
					(thickness 0.15)
				)
			)
		)
		(sheetname "/HDMI + SD Card/")
		(sheetfile "hdmi-sd-card.kicad_sch")
		(attr smd)
		(fp_rect
			(start -0.925 -0.47)
			(end 0.925 0.47)
			(stroke
				(width 0.05)
				(type default)
			)
			(fill no)
			(layer "F.CrtYd")
		)
		(fp_rect
			(start -0.5 -0.25)
			(end 0.5 0.25)
			(stroke
				(width 0.15)
				(type solid)
			)
			(fill no)
			(layer "F.Fab")
		)
		(fp_text user "Author: Antmicro"
			(at -0.95 4.169 270)
			(layer "F.Fab")
			(effects
				(font
					(size 0.7 0.7)
					(thickness 0.15)
				)
				(justify left bottom)
			)
		)
		(fp_text user "License: Apache-2.0"
			(at -0.95 5.169 270)
			(layer "F.Fab")
			(effects
				(font
					(size 0.7 0.7)
					(thickness 0.15)
				)
				(justify left bottom)
			)
		)
		(fp_text user "${REFERENCE}"
			(at -0.95 3.168 270)
			(layer "F.Fab")
			(effects
				(font
					(size 0.7 0.7)
					(thickness 0.15)
				)
				(justify left bottom)
			)
		)
		(pad "1" smd roundrect
			(at -0.48 0 270)
			(size 0.59 0.64)
			(layers "F.Cu" "F.Mask" "F.Paste")
			(roundrect_rratio 0.25)
			(net 1 "GND")
			(pintype "passive")
		)
		(pad "2" smd roundrect
			(at 0.48 0 270)
			(size 0.59 0.64)
			(layers "F.Cu" "F.Mask" "F.Paste")
			(roundrect_rratio 0.25)
			(net 188 "Net-(C132-Pad1)")
			(pintype "passive")
		)
	)
	(footprint "antmicro-footprints:SOD-523"
		(layer "F.Cu")
		(at 115.75 152.5 180)
		(property "Reference" "D19"
			(at -1 1.725 0)
			(layer "F.SilkS")
			(effects
				(font
					(size 0.7 0.7)
					(thickness 0.15)
				)
				(justify right bottom)
			)
		)
		(property "Value" "PESD5V0X1UB"
			(at 0 1.499 0)
			(layer "F.Fab")
			(effects
				(font
					(size 0.7 0.7)
					(thickness 0.15)
				)
				(justify right bottom)
			)
		)
		(property "Datasheet" "https://assets.nexperia.com/documents/data-sheet/PESD5V0X1UB.pdf"
			(at 0 0 180)
			(layer "F.Fab")
			(hide yes)
			(effects
				(font
					(size 1.27 1.27)
					(thickness 0.15)
				)
			)
		)
		(property "MPN" "PESD5V0X1UB,135"
			(at 0 0 180)
			(unlocked yes)
			(layer "F.Fab")
			(hide yes)
			(effects
				(font
					(size 1 1)
					(thickness 0.15)
				)
			)
		)
		(property "Manufacturer" "Nexperia"
			(at 0 0 180)
			(unlocked yes)
			(layer "F.Fab")
			(hide yes)
			(effects
				(font
					(size 1 1)
					(thickness 0.15)
				)
			)
		)
		(property "Author" "Antmicro"
			(at 0 0 180)
			(unlocked yes)
			(layer "F.Fab")
			(hide yes)
			(effects
				(font
					(size 1 1)
					(thickness 0.15)
				)
			)
		)
		(property "License" "Apache-2.0"
			(at 0 0 180)
			(unlocked yes)
			(layer "F.Fab")
			(hide yes)
			(effects
				(font
					(size 1 1)
					(thickness 0.15)
				)
			)
		)
		(sheetname "/HDMI + SD Card/")
		(sheetfile "hdmi-sd-card.kicad_sch")
		(attr smd)
		(fp_line
			(start -0.35 -0.5)
			(end -0.35 0.5)
			(stroke
				(width 0.15)
				(type solid)
			)
			(layer "F.SilkS")
		)
		(fp_rect
			(start -1 -0.6)
			(end 1 0.6)
			(stroke
				(width 0.05)
				(type solid)
			)
			(fill no)
			(layer "F.CrtYd")
		)
		(fp_line
			(start 0.65 -0.425)
			(end 0.65 0.423)
			(stroke
				(width 0.15)
				(type solid)
			)
			(layer "F.Fab")
		)
		(fp_line
			(start -0.35 -0.4)
			(end -0.35 0.4)
			(stroke
				(width 0.15)
				(type solid)
			)
			(layer "F.Fab")
		)
		(fp_line
			(start -0.652 0.423)
			(end 0.65 0.423)
			(stroke
				(width 0.15)
				(type solid)
			)
			(layer "F.Fab")
		)
		(fp_line
			(start -0.652 0.423)
			(end -0.652 -0.425)
			(stroke
				(width 0.15)
				(type solid)
			)
			(layer "F.Fab")
		)
		(fp_line
			(start -0.652 -0.425)
			(end 0.65 -0.425)
			(stroke
				(width 0.15)
				(type solid)
			)
			(layer "F.Fab")
		)
		(fp_text user "Author: Antmicro"
			(at -1.276 4.7 180)
			(layer "F.Fab")
			(effects
				(font
					(size 0.7 0.7)
					(thickness 0.15)
				)
				(justify left bottom)
			)
		)
		(fp_text user "License: Apache-2.0"
			(at -1.276 5.9 180)
			(layer "F.Fab")
			(effects
				(font
					(size 0.7 0.7)
					(thickness 0.15)
				)
				(justify left bottom)
			)
		)
		(fp_text user "${REFERENCE}"
			(at -1.276 3.499 180)
			(layer "F.Fab")
			(effects
				(font
					(size 0.7 0.7)
					(thickness 0.15)
				)
				(justify left bottom)
			)
		)
		(pad "1" smd roundrect
			(at -0.701 0 180)
			(size 0.5 0.6)
			(layers "F.Cu" "F.Mask" "F.Paste")
			(roundrect_rratio 0.25)
			(net 635 "/FPGA banks HP/SD.CD")
			(pinfunction "C")
			(pintype "passive")
		)
		(pad "2" smd roundrect
			(at 0.699 0 180)
			(size 0.5 0.6)
			(layers "F.Cu" "F.Mask" "F.Paste")
			(roundrect_rratio 0.25)
			(net 1 "GND")
			(pinfunction "A")
			(pintype "passive")
		)
	)
)
